FILE_TYPE = MACRO_DRAWING;
SET COLOR_WIRE YELLOW;
SET COLOR_PROP ORANGE;
SET COLOR_DOT WHITE;
SET COLOR_ARC YELLOW;
SET COLOR_BODY GREEN;
SET COLOR_NOTE PURPLE;
SET PROP_DISPLAY VALUE;
SET PAGE_NUMBER P36;
FORCEADD QUANTA_TITLE_BLOCK_C..1
(0 0);
FORCEPROP 1 LAST CUSTOM_TXT_CDS <NAME_2>
J 0
(-3175 50);
FORCEPROP 1 LAST CUSTOM_TXT_CDS <NAME_1>
J 0
(-3175 175);
FORCEPROP 1 LAST CUSTOM_TXT_CDS <Q_NUMBER>
J 0
(-1403 103);
DISPLAY 1.212766 (-1403 103);
FORCEPROP 1 LAST CUSTOM_TXT_CDS <Q_PROJ>
J 0
(-2382 102);
DISPLAY 1.212766 (-2382 102);
FORCEPROP 1 LAST CUSTOM_TXT_CDS <Q_REV>
J 0
(-184 103);
DISPLAY 1.212766 (-184 103);
FORCEPROP 1 LAST CUSTOM_TXT_CDS <CON_LAST_MODIFIED>
J 0
(-1885 15);
DISPLAY 0.978723 (-1885 15);
FORCEPROP 1 LAST CUSTOM_TXT_CDS <CON_PAGE_NUM> OF <CON_TOTAL_PAGES>
J 0
(-446 18);
DISPLAY 0.978723 (-446 18);
FORCEPROP 1 LAST Q_DEPT BU9
J 1
(-3763 49);
DISPLAY 1.957447 (-3763 49);
PAINT GREEN (-3763 49);
FORCEPROP 1 LAST Q_TITLE Blank
J 0
(-9300 50);
DISPLAY 2.446809 (-9300 50);
PAINT GREEN (-9300 50);
FORCEPROP 0 LAST CDS_CON_LAST_MODIFIED Wed Jul 21 11:34:34 2021
J 0
(-1885 15);
DISPLAY INVISIBLE (-1885 15);
FORCEPROP 1 LAST CDS_LMAN_SYM_OUTLINE -9475,6775,100,-125
J 0
(0 0);
DISPLAY 0.468085 (0 0);
PAINT GREEN (0 0);
DISPLAY INVISIBLE (0 0);
FORCEPROP 2 LAST CDS_LIB pure_quanta
J 0
(0 0);
DISPLAY INVISIBLE (0 0);
FORCEPROP 2 LAST PAGE_BORDER TRUE
J 0
(-7890 5250);
DISPLAY 0.638298 (-7890 5250);
PAINT PINK (-7890 5250);
DISPLAY INVISIBLE (-7890 5250);
FORCEPROP 1 LAST COMMENT_BODY TRUE
J 0
(12 -13);
DISPLAY 0.978723 (12 -13);
PAINT GREEN (12 -13);
DISPLAY INVISIBLE (12 -13);
FORCEPROP 2 LAST CUSTOM_TXT_CDS <XR_PAGE_TITLE>
J 0
(-7890 5250);
DISPLAY 0.638298 (-7890 5250);
PAINT PINK (-7890 5250);
DISPLAY INVISIBLE (-7890 5250);
FORCEPROP 2 LAST CDS_XR_PAGE_TITLE CR-36 : @T6G_MB_LIB.T6G(SCH_1):PAGE36
J 0
(-7890 5250);
DISPLAY 0.638298 (-7890 5250);
PAINT PINK (-7890 5250);
DISPLAY INVISIBLE (-7890 5250);
QUIT
